FILE_TYPE = MULTI_PHYS_TABLE;

PART 'CL5003148A'
CLASS=IC

{========================================================================================}
:CLS_PN       = JEDEC_TYPE         | ALT_SYMBOLS          | DESCRIPTION                                                                       ;
{========================================================================================}
 'CL5003148A'(!) = 'SC70_5V1' | '(SC70_5V1)' | 'IC, AND GATE, SINGLE, 2-INPUT, POSITIVE, SC-70'
 'G220-00019-01'(!) = 'SOT23_5' | '(SOT23_5)' | 'IC,74LVC1G86,SINGLE_XOR,SOT23-5'
 'G220-10318-01'(!) = 'SC70_5V1' | '(SC70_5V1)' | 'IC,SN74LVC1G86DCKR,SINGLE 2-INPUT EXCLUSIVE-OR GATE,SC70 '
 'G220-10019-01'(!) = 'SC70_5V1' | '(SC70_5V1)' | 'IC,74LVC1G32,SINGLE 2_INPUT POSITIVE OR GATE,SC70_5'
 'G220-10033-01'(!) = 'SOT23_5_V1' | '(SOT23_5_V1)' | 'IC,NC7SZ02,SINGLE NOR GATE,SOT23'
 
END_PART

END.

